# T6G (Grand Teton) — schematic netlist excerpt (pin names and nets, part order shuffled) for the footprints in the layout excerpt that follows; sources: Cadence DE-HDL packaged netlist, KiCad conversion of 04192023_DAF0TMB3IC0_F0TG_MB_C_brd_V02_OCP.brd

PU2  ISL99390FRZTR5935  ISL99390FRZ-TR5935 IC  pkg QFN21_6X5XB  page 201
  VOS  = PVDDCR_CPU1_P0_VOS2
  AGND  = GND
  VCC  = PVDDCR_CPU1_P0_VCC2
  PVCC  = PVDDCR_CPU1_P0_PVCC
  PGND1  = GND
  GL1  = NC_PVDDCR_CPU1_P0_GL1_2
  PGND2  = GND
  SW  = SW_PVDDCR_CPU1_P0_SW2
  VIN1  = SW_P12V_AUX_PVDDCR_CPU1_P0_FLT
  VIN2  = SW_P12V_AUX_PVDDCR_CPU1_P0_FLT
  DNC  = NC_PVDDCR_CPU1_P0_DNC2
  PHASE  = SW_PVDDCR_CPU1_P0_BOOTR2
  BOOT  = SW_PVDDCR_CPU1_P0_BOOT2
  PWM  = PVDDCR_CPU1_P0_PWM2
  EN  = PVDDCR_CPU1_P0_VCC2
  TOUT_FLT  = PVDDCR_CPU1_P0_TEMP0
  LSET  = PVDDCR_CPU1_P0_LSET2
  IOUT  = PVDDCR_CPU1_P0_IMON2
  REFIN  = PVDDCR_CPU1_P0_VCCS
  PGND3  = GND
  GL2  = NC_PVDDCR_CPU1_P0_GL2_2

(kicad_pcb
	(version 20260206)
	(generator "pcbnew")
	(generator_version "10.0")
	(general
		(thickness 1.6)
		(legacy_teardrops no)
	)
	(paper "A4")
	(title_block
		(title "04192023_DAF0TMB3IC0_F0TG_MB_C_brd_V02_OCP.brd")
		(comment 1 "Grand Teton / footprints 4723-4723 of 8354")
	)
	(layers
		(0 "F.Cu" signal "TOP")
		(4 "In1.Cu" signal "GND")
		(6 "In2.Cu" signal "IN1")
		(8 "In3.Cu" signal "GND1")
		(10 "In4.Cu" signal "IN2")
		(12 "In5.Cu" signal "GND2")
		(14 "In6.Cu" signal "IN3")
		(16 "In7.Cu" signal "GND3")
		(18 "In8.Cu" signal "VCC")
		(20 "In9.Cu" signal "VCC1")
		(22 "In10.Cu" signal "GND4")
		(24 "In11.Cu" signal "IN4")
		(26 "In12.Cu" signal "GND5")
		(28 "In13.Cu" signal "IN5")
		(30 "In14.Cu" signal "GND6")
		(32 "In15.Cu" signal "IN6")
		(34 "In16.Cu" signal "GND7")
		(2 "B.Cu" signal "BOTTOM")
		(9 "F.Adhes" user "F.Adhesive")
		(11 "B.Adhes" user "B.Adhesive")
		(13 "F.Paste" user "Package Geometry/Pastemask Top")
		(15 "B.Paste" user "Package Geometry/Pastemask Bottom")
		(5 "F.SilkS" user "Ref Des/Silkscreen Top")
		(7 "B.SilkS" user "Ref Des/Silkscreen Bottom")
		(1 "F.Mask" user "Board Geometry/Soldermask Top")
		(3 "B.Mask" user "Board Geometry/Soldermask Bottom")
		(17 "Dwgs.User" user "User.Drawings")
		(19 "Cmts.User" user "User.Comments")
		(21 "Eco1.User" user "User.Eco1")
		(23 "Eco2.User" user "User.Eco2")
		(25 "Edge.Cuts" user "Board Geometry/Outline")
		(27 "Margin" user)
		(31 "F.CrtYd" user "Package Geometry/Place Bound Top")
		(29 "B.CrtYd" user "Package Geometry/Place Bound Bottom")
		(35 "F.Fab" user "Ref Des/Assembly Top")
		(33 "B.Fab" user "Ref Des/Assembly Bottom")
	)
	(footprint ""
		(layer "F.Cu")
		(at 326.701404 -334.988154)
		(property "Reference" "PU2"
			(at 0.450596 -7.631176 0)
			(unlocked yes)
			(layer "F.SilkS")
			(effects
				(font
					(size 0.7874 0.5842)
					(thickness 0.1524)
				)
				(justify left)
			)
		)
		(property "Value" ""
			(at 0 0 0)
			(layer "F.Fab")
			(effects
				(font
					(size 1.27 1.27)
				)
			)
		)
		(duplicate_pad_numbers_are_jumpers no)
		(fp_line
			(start -2.500122 -2.999994)
			(end -2.24409 -2.999994)
			(stroke
				(width 0.1524)
				(type default)
			)
			(layer "F.SilkS")
		)
		(fp_line
			(start -2.500122 -2.529078)
			(end -2.500122 -2.999994)
			(stroke
				(width 0.1524)
				(type default)
			)
			(layer "F.SilkS")
		)
		(fp_line
			(start -2.500122 0.6604)
			(end -2.500122 0.229108)
			(stroke
				(width 0.1524)
				(type default)
			)
			(layer "F.SilkS")
		)
		(fp_line
			(start -2.500122 2.999994)
			(end -2.500122 2.339594)
			(stroke
				(width 0.1524)
				(type default)
			)
			(layer "F.SilkS")
		)
		(fp_line
			(start -2.2987 2.999994)
			(end -2.500122 2.999994)
			(stroke
				(width 0.1524)
				(type default)
			)
			(layer "F.SilkS")
		)
		(fp_line
			(start 2.31394 -2.999994)
			(end 2.500122 -2.999994)
			(stroke
				(width 0.1524)
				(type default)
			)
			(layer "F.SilkS")
		)
		(fp_line
			(start 2.500122 -2.999994)
			(end 2.500122 -2.44348)
			(stroke
				(width 0.1524)
				(type default)
			)
			(layer "F.SilkS")
		)
		(fp_line
			(start 2.500122 2.339594)
			(end 2.500122 2.999994)
			(stroke
				(width 0.1524)
				(type default)
			)
			(layer "F.SilkS")
		)
		(fp_line
			(start 2.500122 2.999994)
			(end 2.2987 2.999994)
			(stroke
				(width 0.1524)
				(type default)
			)
			(layer "F.SilkS")
		)
		(fp_poly
			(pts
				(xy -2.774442 -2.272284) (xy -3.409442 -1.954784) (xy -3.409442 -2.589784)
			)
			(stroke
				(width 0)
				(type default)
			)
			(fill yes)
			(layer "F.SilkS")
		)
		(fp_line
			(start -2.500122 -2.999994)
			(end 2.500122 -2.999994)
			(stroke
				(width 0.1)
				(type default)
			)
			(layer "F.Fab")
		)
		(fp_line
			(start -2.500122 2.999994)
			(end -2.500122 -2.999994)
			(stroke
				(width 0.1)
				(type default)
			)
			(layer "F.Fab")
		)
		(fp_line
			(start 2.500122 -2.999994)
			(end 2.500122 2.999994)
			(stroke
				(width 0.1)
				(type default)
			)
			(layer "F.Fab")
		)
		(fp_line
			(start 2.500122 2.999994)
			(end -2.500122 2.999994)
			(stroke
				(width 0.1)
				(type default)
			)
			(layer "F.Fab")
		)
		(fp_poly
			(pts
				(xy -4.218432 -2.783078) (xy -4.218432 -1.767078) (xy -3.202432 -2.275078)
			)
			(stroke
				(width 0)
				(type default)
			)
			(fill yes)
			(layer "F.Fab")
		)
		(pad "1" smd rect
			(at -2.400046 -2.275078 90)
			(size 0.2286 0.6096)
			(layers "F.Cu" "F.Mask" "F.Paste")
			(net "PVDDCR_CPU1_P0_VOS2")
		)
		(pad "2" smd rect
			(at -2.400046 -1.82499 90)
			(size 0.2286 0.6096)
			(layers "F.Cu" "F.Mask" "F.Paste")
			(net "GND")
		)
		(pad "3" smd rect
			(at -2.400046 -1.374902 90)
			(size 0.2286 0.6096)
			(layers "F.Cu" "F.Mask" "F.Paste")
			(net "PVDDCR_CPU1_P0_VCC2")
		)
		(pad "4" smd rect
			(at -2.400046 -0.925068 90)
			(size 0.2286 0.6096)
			(layers "F.Cu" "F.Mask" "F.Paste")
			(net "PVDDCR_CPU1_P0_PVCC")
		)
		(pad "5" smd rect
			(at -2.400046 -0.47498 90)
			(size 0.2286 0.6096)
			(layers "F.Cu" "F.Mask" "F.Paste")
			(net "GND")
		)
		(pad "6" smd rect
			(at -2.400046 -0.024892 90)
			(size 0.2286 0.6096)
			(layers "F.Cu" "F.Mask" "F.Paste")
			(net "NC_PVDDCR_CPU1_P0_GL1_2")
		)
		(pad "7_9-20_24" smd circle
			(at 0 1.150112 90)
			(size 0 0)
			(layers "F.Cu" "F.Mask" "F.Paste")
			(net "GND")
		)
		(pad "10_19" smd rect
			(at 0 2.899918 90)
			(size 0.6096 4.318)
			(layers "F.Cu" "F.Mask" "F.Paste")
			(net "SW_PVDDCR_CPU1_P0_SW2")
		)
		(pad "25_29" smd rect
			(at 1.549908 -1.279906 270)
			(size 2.0574 2.3114)
			(layers "F.Cu" "F.Mask" "F.Paste")
			(net "SW_P12V_AUX_PVDDCR_CPU1_P0_FLT")
		)
		(pad "30" smd rect
			(at 2.05994 -2.899918)
			(size 0.2286 0.6096)
			(layers "F.Cu" "F.Mask" "F.Paste")
			(net "SW_P12V_AUX_PVDDCR_CPU1_P0_FLT")
		)
		(pad "31" smd rect
			(at 1.610106 -2.899918)
			(size 0.2286 0.6096)
			(layers "F.Cu" "F.Mask" "F.Paste")
			(net "NC_PVDDCR_CPU1_P0_DNC2")
		)
		(pad "32" smd rect
			(at 1.160018 -2.899918)
			(size 0.2286 0.6096)
			(layers "F.Cu" "F.Mask" "F.Paste")
			(net "SW_PVDDCR_CPU1_P0_BOOTR2")
		)
		(pad "33" smd rect
			(at 0.70993 -2.899918)
			(size 0.2286 0.6096)
			(layers "F.Cu" "F.Mask" "F.Paste")
			(net "SW_PVDDCR_CPU1_P0_BOOT2")
		)
		(pad "34" smd rect
			(at 0.260096 -2.899918)
			(size 0.2286 0.6096)
			(layers "F.Cu" "F.Mask" "F.Paste")
			(net "PVDDCR_CPU1_P0_PWM2")
		)
		(pad "35" smd rect
			(at -0.189992 -2.899918)
			(size 0.2286 0.6096)
			(layers "F.Cu" "F.Mask" "F.Paste")
			(net "PVDDCR_CPU1_P0_VCC2")
		)
		(pad "36" smd rect
			(at -0.64008 -2.899918)
			(size 0.2286 0.6096)
			(layers "F.Cu" "F.Mask" "F.Paste")
			(net "PVDDCR_CPU1_P0_TEMP0")
		)
		(pad "37" smd rect
			(at -1.089914 -2.899918)
			(size 0.2286 0.6096)
			(layers "F.Cu" "F.Mask" "F.Paste")
			(net "PVDDCR_CPU1_P0_LSET2")
		)
		(pad "38" smd rect
			(at -1.540002 -2.899918)
			(size 0.2286 0.6096)
			(layers "F.Cu" "F.Mask" "F.Paste")
			(net "PVDDCR_CPU1_P0_IMON2")
		)
		(pad "39" smd rect
			(at -1.99009 -2.899918)
			(size 0.2286 0.6096)
			(layers "F.Cu" "F.Mask" "F.Paste")
			(net "PVDDCR_CPU1_P0_VCCS")
		)
		(pad "40" smd rect
			(at -0.87503 -1.27508)
			(size 1.7526 1.9558)
			(layers "F.Cu" "F.Mask" "F.Paste")
			(net "GND")
		)
		(pad "41" smd rect
			(at -1.525016 0.249936 270)
			(size 0.3048 0.4572)
			(layers "F.Cu" "F.Mask" "F.Paste")
			(net "NC_PVDDCR_CPU1_P0_GL2_2")
		)
		(zone
			(layer "F.Cu")
			(hatch none 0.5)
			(connect_pads
				(clearance 0)
			)
			(min_thickness 0.25)
			(keepout
				(tracks not_allowed)
				(vias allowed)
				(pads allowed)
				(copperpour not_allowed)
				(footprints allowed)
			)
			(placement
				(enabled no)
				(sheetname "")
			)
			(fill
				(thermal_gap 0.5)
				(thermal_bridge_width 0.5)
				(island_removal_mode 0)
			)
			(polygon
				(pts
					(xy 324.201282 -332.418182) (xy 324.201282 -332.73746) (xy 329.201526 -332.73746) (xy 329.201526 -332.406498)
					(xy 328.911204 -332.406498) (xy 328.911204 -332.443836) (xy 324.491604 -332.443836) (xy 324.491604 -332.418182)
				)
			)
		)
		(zone
			(layer "F.Cu")
			(hatch none 0.5)
			(connect_pads
				(clearance 0)
			)
			(min_thickness 0.25)
			(keepout
				(tracks not_allowed)
				(vias allowed)
				(pads allowed)
				(copperpour not_allowed)
				(footprints allowed)
			)
			(placement
				(enabled no)
				(sheetname "")
			)
			(fill
				(thermal_gap 0.5)
				(thermal_bridge_width 0.5)
				(island_removal_mode 0)
			)
			(polygon
				(pts
					(xy 326.753474 -335.234534) (xy 326.753474 -337.291934) (xy 324.899274 -337.291934) (xy 324.899274 -337.050888)
					(xy 324.656958 -337.050888) (xy 324.656958 -337.532472) (xy 328.471022 -337.532472) (xy 328.471022 -337.34756)
					(xy 327.044812 -337.34756) (xy 327.044812 -335.18856) (xy 329.201526 -335.18856) (xy 329.201526 -334.938878)
					(xy 327.04913 -334.938878)
				)
			)
		)
	)
)
